FILE_TYPE = CONNECTIVITY;
{Allegro Design Entry HDL 17.2-2016 S081 (4005846) 1/11/2022}
"PAGE_NUMBER" = 52;
0"NC";
1"M_B_CPU1_SA_CA<6:0>";
2"M_B_CPU1_SA_CS_N<3:0>";
3"M_B_CPU1_SA_DQS_DN<9:0>";
4"M_B_CPU1_SA_DQS_DP<9:0>";
5"M_B_CPU1_SB_CA<6:0>";
6"M_B_CPU1_SB_CS_N<3:0>";
7"M_B_CPU1_SB_DQS_DN<9:0>";
8"M_B_CPU1_SB_DQS_DP<9:0>";
9"M_B_CPU1_SB_CB<7:0>";
10"M_B_CPU1_SB_DQ<31:0>";
11"M_B_CPU1_SA_CB<7:0>";
12"M_B_CPU1_SA_DQ<31:0>";
13"M_B_CPU1_CLK_DP<1:0>";
14"M_B_CPU1_CLK_DN<1:0>";
15"M_B_CPU1_CLK_DN<1>";
16"M_B_CPU1_CLK_DN<0>";
17"M_B_CPU1_CLK_DP<1>";
18"M_B_CPU1_CLK_DP<0>";
19"M_B_CPU1_SA_DQ<31>";
20"M_B_CPU1_SA_DQ<30>";
21"M_B_CPU1_SA_DQ<29>";
22"M_B_CPU1_SA_DQ<28>";
23"M_B_CPU1_SA_DQ<27>";
24"M_B_CPU1_SA_DQ<26>";
25"M_B_CPU1_SA_DQ<25>";
26"M_B_CPU1_SA_DQ<24>";
27"M_B_CPU1_SA_DQ<23>";
28"M_B_CPU1_SA_DQ<22>";
29"M_B_CPU1_SA_DQ<21>";
30"M_B_CPU1_SA_DQ<20>";
31"M_B_CPU1_SA_DQ<19>";
32"M_B_CPU1_SA_DQ<18>";
33"M_B_CPU1_SA_DQ<17>";
34"M_B_CPU1_SA_DQ<16>";
35"M_B_CPU1_SA_DQ<15>";
36"M_B_CPU1_SA_DQ<14>";
37"M_B_CPU1_SA_DQ<13>";
38"M_B_CPU1_SA_DQ<12>";
39"M_B_CPU1_SA_DQ<11>";
40"M_B_CPU1_SA_DQ<10>";
41"M_B_CPU1_SA_DQ<9>";
42"M_B_CPU1_SA_DQ<8>";
43"M_B_CPU1_SA_DQ<7>";
44"M_B_CPU1_SA_DQ<6>";
45"M_B_CPU1_SA_DQ<5>";
46"M_B_CPU1_SA_DQ<4>";
47"M_B_CPU1_SA_DQ<3>";
48"M_B_CPU1_SA_DQ<2>";
49"M_B_CPU1_SA_DQ<1>";
50"M_B_CPU1_SA_DQ<0>";
51"M_B_CPU1_SA_CB<7>";
52"M_B_CPU1_SA_CB<6>";
53"M_B_CPU1_SA_CB<5>";
54"M_B_CPU1_SA_CB<4>";
55"M_B_CPU1_SA_CB<3>";
56"M_B_CPU1_SA_CB<2>";
57"M_B_CPU1_SA_CB<1>";
58"M_B_CPU1_SA_CB<0>";
59"M_B_CPU1_SB_DQ<31>";
60"M_B_CPU1_SB_DQ<30>";
61"M_B_CPU1_SB_DQ<29>";
62"M_B_CPU1_SB_DQ<28>";
63"M_B_CPU1_SB_DQ<27>";
64"M_B_CPU1_SB_DQ<26>";
65"M_B_CPU1_SB_DQ<25>";
66"M_B_CPU1_SB_DQ<24>";
67"M_B_CPU1_SB_DQ<23>";
68"M_B_CPU1_SB_DQ<22>";
69"M_B_CPU1_SB_DQ<21>";
70"M_B_CPU1_SB_DQ<20>";
71"M_B_CPU1_SB_DQ<19>";
72"M_B_CPU1_SB_DQ<18>";
73"M_B_CPU1_SB_DQ<17>";
74"M_B_CPU1_SB_DQ<16>";
75"M_B_CPU1_SB_DQ<15>";
76"M_B_CPU1_SB_DQ<14>";
77"M_B_CPU1_SB_DQ<13>";
78"M_B_CPU1_SB_DQ<12>";
79"M_B_CPU1_SB_DQ<11>";
80"M_B_CPU1_SB_DQ<10>";
81"M_B_CPU1_SB_DQ<9>";
82"M_B_CPU1_SB_DQ<8>";
83"M_B_CPU1_SB_DQ<7>";
84"M_B_CPU1_SB_DQ<6>";
85"M_B_CPU1_SB_DQ<5>";
86"M_B_CPU1_SB_DQ<4>";
87"M_B_CPU1_SB_DQ<3>";
88"M_B_CPU1_SB_DQ<2>";
89"M_B_CPU1_SB_DQ<1>";
90"M_B_CPU1_SB_DQ<0>";
91"M_B_CPU1_SB_CB<7>";
92"M_B_CPU1_SB_CB<6>";
93"M_B_CPU1_SB_CB<5>";
94"M_B_CPU1_SB_CB<4>";
95"M_B_CPU1_SB_CB<3>";
96"M_B_CPU1_SB_CB<2>";
97"M_B_CPU1_SB_CB<1>";
98"M_B_CPU1_SB_CB<0>";
99"M_B_CPU1_SB_PAR";
100"M_B_CPU1_SB_DQS_DP<0>";
101"M_B_CPU1_SB_DQS_DP<1>";
102"M_B_CPU1_SB_DQS_DP<2>";
103"M_B_CPU1_SB_DQS_DP<3>";
104"M_B_CPU1_SB_DQS_DP<4>";
105"M_B_CPU1_SB_DQS_DP<5>";
106"M_B_CPU1_SB_DQS_DP<6>";
107"M_B_CPU1_SB_DQS_DP<7>";
108"M_B_CPU1_SB_DQS_DP<8>";
109"M_B_CPU1_SB_DQS_DP<9>";
110"M_B_CPU1_SB_DQS_DN<0>";
111"M_B_CPU1_SB_DQS_DN<1>";
112"M_B_CPU1_SB_DQS_DN<2>";
113"M_B_CPU1_SB_DQS_DN<3>";
114"M_B_CPU1_SB_DQS_DN<4>";
115"M_B_CPU1_SB_DQS_DN<5>";
116"M_B_CPU1_SB_DQS_DN<6>";
117"M_B_CPU1_SB_DQS_DN<7>";
118"M_B_CPU1_SB_DQS_DN<8>";
119"M_B_CPU1_SB_DQS_DN<9>";
120"M_B_CPU1_SB_CS_N<0>";
121"M_B_CPU1_SB_CS_N<1>";
122"M_B_CPU1_SB_CS_N<2>";
123"M_B_CPU1_SB_CS_N<3>";
124"M_B_CPU1_SB_CA<0>";
125"M_B_CPU1_SB_CA<1>";
126"M_B_CPU1_SB_CA<2>";
127"M_B_CPU1_SB_CA<3>";
128"M_B_CPU1_SB_CA<4>";
129"M_B_CPU1_SB_CA<5>";
130"M_B_CPU1_SB_CA<6>";
131"M_B_CPU1_SA_PAR";
132"M_B_CPU1_SA_DQS_DP<0>";
133"M_B_CPU1_SA_DQS_DP<1>";
134"M_B_CPU1_SA_DQS_DP<2>";
135"M_B_CPU1_SA_DQS_DP<3>";
136"M_B_CPU1_SA_DQS_DP<4>";
137"M_B_CPU1_SA_DQS_DP<5>";
138"M_B_CPU1_SA_DQS_DP<6>";
139"M_B_CPU1_SA_DQS_DP<7>";
140"M_B_CPU1_SA_DQS_DP<8>";
141"M_B_CPU1_SA_DQS_DP<9>";
142"M_B_CPU1_SA_DQS_DN<0>";
143"M_B_CPU1_SA_DQS_DN<1>";
144"M_B_CPU1_SA_DQS_DN<2>";
145"M_B_CPU1_SA_DQS_DN<3>";
146"M_B_CPU1_SA_DQS_DN<4>";
147"M_B_CPU1_SA_DQS_DN<5>";
148"M_B_CPU1_SA_DQS_DN<6>";
149"M_B_CPU1_SA_DQS_DN<7>";
150"M_B_CPU1_SA_DQS_DN<8>";
151"M_B_CPU1_SA_DQS_DN<9>";
152"M_B_CPU1_SA_CS_N<0>";
153"M_B_CPU1_SA_CS_N<1>";
154"M_B_CPU1_SA_CS_N<2>";
155"M_B_CPU1_SA_CS_N<3>";
156"M_B_CPU1_SA_CA<0>";
157"M_B_CPU1_SA_CA<1>";
158"M_B_CPU1_SA_CA<2>";
159"M_B_CPU1_SA_CA<3>";
160"M_B_CPU1_SA_CA<4>";
161"M_B_CPU1_SA_CA<5>";
162"M_B_CPU1_SA_CA<6>";
163"M_B_CPU1_SB_RSP<0>";
164"M_B_CPU1_SB_RSP<1>";
165"M_B_CPU1_SA_RSP<0>";
166"M_B_CPU1_SA_RSP<1>";
167"M_B_CPU1_ALERT_N";
%"TAP"
"1","(-950,-50)","2","standard","I10";
;
CDS_LIB"standard"
BODY_TYPE"PLUMBING"
HDL_TAP"TRUE";
"B \NAC \NWC"9;
"S \NAC"
BN"0"98;
%"TAP"
"1","(2475,450)","0","standard","I100";
;
CDS_LIB"standard"
BODY_TYPE"PLUMBING"
HDL_TAP"TRUE";
"B \NAC \NWC"2;
"S \NAC"
BN"0"152;
%"TAP"
"1","(2475,550)","0","standard","I101";
;
CDS_LIB"standard"
BODY_TYPE"PLUMBING"
HDL_TAP"TRUE";
"B \NAC \NWC"2;
"S \NAC"
BN"2"154;
%"TAP"
"1","(2475,500)","0","standard","I102";
;
CDS_LIB"standard"
BODY_TYPE"PLUMBING"
HDL_TAP"TRUE";
"B \NAC \NWC"2;
"S \NAC"
BN"1"153;
%"TAP"
"1","(2475,600)","0","standard","I103";
;
CDS_LIB"standard"
BODY_TYPE"PLUMBING"
HDL_TAP"TRUE";
"B \NAC \NWC"2;
"S \NAC"
BN"3"155;
%"TAP"
"1","(2475,850)","0","standard","I104";
;
CDS_LIB"standard"
BODY_TYPE"PLUMBING"
HDL_TAP"TRUE";
"B \NAC \NWC"5;
"S \NAC"
BN"1"125;
%"TAP"
"1","(2475,800)","0","standard","I105";
;
CDS_LIB"standard"
BODY_TYPE"PLUMBING"
HDL_TAP"TRUE";
"B \NAC \NWC"5;
"S \NAC"
BN"0"124;
%"TAP"
"1","(2475,900)","0","standard","I106";
;
CDS_LIB"standard"
BODY_TYPE"PLUMBING"
HDL_TAP"TRUE";
"B \NAC \NWC"5;
"S \NAC"
BN"2"126;
%"TAP"
"1","(2475,1100)","0","standard","I107";
;
CDS_LIB"standard"
BODY_TYPE"PLUMBING"
HDL_TAP"TRUE";
"B \NAC \NWC"5;
"S \NAC"
BN"6"130;
%"TAP"
"1","(2475,1050)","0","standard","I108";
;
CDS_LIB"standard"
BODY_TYPE"PLUMBING"
HDL_TAP"TRUE";
"B \NAC \NWC"5;
"S \NAC"
BN"5"129;
%"TAP"
"1","(2475,1000)","0","standard","I109";
;
CDS_LIB"standard"
BODY_TYPE"PLUMBING"
HDL_TAP"TRUE";
"B \NAC \NWC"5;
"S \NAC"
BN"4"128;
%"TAP"
"1","(-950,50)","2","standard","I11";
;
CDS_LIB"standard"
BODY_TYPE"PLUMBING"
HDL_TAP"TRUE";
"B \NAC \NWC"9;
"S \NAC"
BN"2"96;
%"TAP"
"1","(2475,950)","0","standard","I110";
;
CDS_LIB"standard"
BODY_TYPE"PLUMBING"
HDL_TAP"TRUE";
"B \NAC \NWC"5;
"S \NAC"
BN"3"127;
%"TAP"
"1","(2475,1350)","0","standard","I111";
;
CDS_LIB"standard"
BODY_TYPE"PLUMBING"
HDL_TAP"TRUE";
"B \NAC \NWC"1;
"S \NAC"
BN"1"157;
%"TAP"
"1","(2475,1400)","0","standard","I112";
;
CDS_LIB"standard"
BODY_TYPE"PLUMBING"
HDL_TAP"TRUE";
"B \NAC \NWC"1;
"S \NAC"
BN"2"158;
%"TAP"
"1","(2475,1450)","0","standard","I113";
;
CDS_LIB"standard"
BODY_TYPE"PLUMBING"
HDL_TAP"TRUE";
"B \NAC \NWC"1;
"S \NAC"
BN"3"159;
%"TAP"
"1","(2475,1300)","0","standard","I114";
;
CDS_LIB"standard"
BODY_TYPE"PLUMBING"
HDL_TAP"TRUE";
"B \NAC \NWC"1;
"S \NAC"
BN"0"156;
%"TAP"
"1","(2475,1500)","0","standard","I115";
;
CDS_LIB"standard"
BODY_TYPE"PLUMBING"
HDL_TAP"TRUE";
"B \NAC \NWC"1;
"S \NAC"
BN"4"160;
%"TAP"
"1","(2475,1600)","0","standard","I116";
;
CDS_LIB"standard"
BODY_TYPE"PLUMBING"
HDL_TAP"TRUE";
"B \NAC \NWC"1;
"S \NAC"
BN"6"162;
%"TAP"
"1","(2475,1550)","0","standard","I117";
;
CDS_LIB"standard"
BODY_TYPE"PLUMBING"
HDL_TAP"TRUE";
"B \NAC \NWC"1;
"S \NAC"
BN"5"161;
%"TAP"
"1","(2475,1800)","0","standard","I118";
;
CDS_LIB"standard"
BODY_TYPE"PLUMBING"
HDL_TAP"TRUE";
"B \NAC \NWC"7;
"S \NAC"
BN"1"111;
%"TAP"
"1","(2475,1950)","0","standard","I119";
;
CDS_LIB"standard"
BODY_TYPE"PLUMBING"
HDL_TAP"TRUE";
"B \NAC \NWC"7;
"S \NAC"
BN"4"114;
%"TAP"
"1","(-950,100)","2","standard","I12";
;
CDS_LIB"standard"
BODY_TYPE"PLUMBING"
HDL_TAP"TRUE";
"B \NAC \NWC"9;
"S \NAC"
BN"3"95;
%"TAP"
"1","(2475,1900)","0","standard","I120";
;
CDS_LIB"standard"
BODY_TYPE"PLUMBING"
HDL_TAP"TRUE";
"B \NAC \NWC"7;
"S \NAC"
BN"3"113;
%"TAP"
"1","(2475,1850)","0","standard","I121";
;
CDS_LIB"standard"
BODY_TYPE"PLUMBING"
HDL_TAP"TRUE";
"B \NAC \NWC"7;
"S \NAC"
BN"2"112;
%"TAP"
"1","(2475,1750)","0","standard","I122";
;
CDS_LIB"standard"
BODY_TYPE"PLUMBING"
HDL_TAP"TRUE";
"B \NAC \NWC"7;
"S \NAC"
BN"0"110;
%"TAP"
"1","(2475,2200)","0","standard","I123";
;
CDS_LIB"standard"
BODY_TYPE"PLUMBING"
HDL_TAP"TRUE";
"B \NAC \NWC"7;
"S \NAC"
BN"9"119;
%"TAP"
"1","(2475,2150)","0","standard","I124";
;
CDS_LIB"standard"
BODY_TYPE"PLUMBING"
HDL_TAP"TRUE";
"B \NAC \NWC"7;
"S \NAC"
BN"8"118;
%"TAP"
"1","(2475,2100)","0","standard","I125";
;
CDS_LIB"standard"
BODY_TYPE"PLUMBING"
HDL_TAP"TRUE";
"B \NAC \NWC"7;
"S \NAC"
BN"7"117;
%"TAP"
"1","(2475,2050)","0","standard","I126";
;
CDS_LIB"standard"
BODY_TYPE"PLUMBING"
HDL_TAP"TRUE";
"B \NAC \NWC"7;
"S \NAC"
BN"6"116;
%"TAP"
"1","(2475,2000)","0","standard","I127";
;
CDS_LIB"standard"
BODY_TYPE"PLUMBING"
HDL_TAP"TRUE";
"B \NAC \NWC"7;
"S \NAC"
BN"5"115;
%"TAP"
"1","(2475,2350)","0","standard","I128";
;
CDS_LIB"standard"
BODY_TYPE"PLUMBING"
HDL_TAP"TRUE";
"B \NAC \NWC"8;
"S \NAC"
BN"1"101;
%"TAP"
"1","(2475,2400)","0","standard","I129";
;
CDS_LIB"standard"
BODY_TYPE"PLUMBING"
HDL_TAP"TRUE";
"B \NAC \NWC"8;
"S \NAC"
BN"2"102;
%"TAP"
"1","(-950,150)","2","standard","I13";
;
CDS_LIB"standard"
BODY_TYPE"PLUMBING"
HDL_TAP"TRUE";
"B \NAC \NWC"9;
"S \NAC"
BN"4"94;
%"TAP"
"1","(2475,2450)","0","standard","I130";
;
CDS_LIB"standard"
BODY_TYPE"PLUMBING"
HDL_TAP"TRUE";
"B \NAC \NWC"8;
"S \NAC"
BN"3"103;
%"TAP"
"1","(2475,2300)","0","standard","I131";
;
CDS_LIB"standard"
BODY_TYPE"PLUMBING"
HDL_TAP"TRUE";
"B \NAC \NWC"8;
"S \NAC"
BN"0"100;
%"TAP"
"1","(2475,2550)","0","standard","I132";
;
CDS_LIB"standard"
BODY_TYPE"PLUMBING"
HDL_TAP"TRUE";
"B \NAC \NWC"8;
"S \NAC"
BN"5"105;
%"TAP"
"1","(2475,2700)","0","standard","I133";
;
CDS_LIB"standard"
BODY_TYPE"PLUMBING"
HDL_TAP"TRUE";
"B \NAC \NWC"8;
"S \NAC"
BN"8"108;
%"TAP"
"1","(2475,2650)","0","standard","I134";
;
CDS_LIB"standard"
BODY_TYPE"PLUMBING"
HDL_TAP"TRUE";
"B \NAC \NWC"8;
"S \NAC"
BN"7"107;
%"TAP"
"1","(2475,2600)","0","standard","I135";
;
CDS_LIB"standard"
BODY_TYPE"PLUMBING"
HDL_TAP"TRUE";
"B \NAC \NWC"8;
"S \NAC"
BN"6"106;
%"TAP"
"1","(2475,2500)","0","standard","I136";
;
CDS_LIB"standard"
BODY_TYPE"PLUMBING"
HDL_TAP"TRUE";
"B \NAC \NWC"8;
"S \NAC"
BN"4"104;
%"TAP"
"1","(2475,2750)","0","standard","I137";
;
CDS_LIB"standard"
BODY_TYPE"PLUMBING"
HDL_TAP"TRUE";
"B \NAC \NWC"8;
"S \NAC"
BN"9"109;
%"TAP"
"1","(2475,2900)","0","standard","I138";
;
CDS_LIB"standard"
BODY_TYPE"PLUMBING"
HDL_TAP"TRUE";
"B \NAC \NWC"3;
"S \NAC"
BN"0"142;
%"TAP"
"1","(2475,2950)","0","standard","I139";
;
CDS_LIB"standard"
BODY_TYPE"PLUMBING"
HDL_TAP"TRUE";
"B \NAC \NWC"3;
"S \NAC"
BN"1"143;
%"TAP"
"1","(-950,200)","2","standard","I14";
;
CDS_LIB"standard"
BODY_TYPE"PLUMBING"
HDL_TAP"TRUE";
"B \NAC \NWC"9;
"S \NAC"
BN"5"93;
%"TAP"
"1","(2475,3050)","0","standard","I140";
;
CDS_LIB"standard"
BODY_TYPE"PLUMBING"
HDL_TAP"TRUE";
"B \NAC \NWC"3;
"S \NAC"
BN"3"145;
%"TAP"
"1","(2475,3200)","0","standard","I141";
;
CDS_LIB"standard"
BODY_TYPE"PLUMBING"
HDL_TAP"TRUE";
"B \NAC \NWC"3;
"S \NAC"
BN"6"148;
%"TAP"
"1","(2475,3250)","0","standard","I142";
;
CDS_LIB"standard"
BODY_TYPE"PLUMBING"
HDL_TAP"TRUE";
"B \NAC \NWC"3;
"S \NAC"
BN"7"149;
%"TAP"
"1","(2475,3150)","0","standard","I143";
;
CDS_LIB"standard"
BODY_TYPE"PLUMBING"
HDL_TAP"TRUE";
"B \NAC \NWC"3;
"S \NAC"
BN"5"147;
%"TAP"
"1","(2475,3100)","0","standard","I144";
;
CDS_LIB"standard"
BODY_TYPE"PLUMBING"
HDL_TAP"TRUE";
"B \NAC \NWC"3;
"S \NAC"
BN"4"146;
%"TAP"
"1","(2475,3000)","0","standard","I145";
;
CDS_LIB"standard"
BODY_TYPE"PLUMBING"
HDL_TAP"TRUE";
"B \NAC \NWC"3;
"S \NAC"
BN"2"144;
%"TAP"
"1","(2475,3300)","0","standard","I146";
;
CDS_LIB"standard"
BODY_TYPE"PLUMBING"
HDL_TAP"TRUE";
"B \NAC \NWC"3;
"S \NAC"
BN"8"150;
%"TAP"
"1","(2475,3500)","0","standard","I147";
;
CDS_LIB"standard"
BODY_TYPE"PLUMBING"
HDL_TAP"TRUE";
"B \NAC \NWC"4;
"S \NAC"
BN"1"133;
%"TAP"
"1","(2475,3450)","0","standard","I148";
;
CDS_LIB"standard"
BODY_TYPE"PLUMBING"
HDL_TAP"TRUE";
"B \NAC \NWC"4;
"S \NAC"
BN"0"132;
%"TAP"
"1","(2475,3350)","0","standard","I149";
;
CDS_LIB"standard"
BODY_TYPE"PLUMBING"
HDL_TAP"TRUE";
"B \NAC \NWC"3;
"S \NAC"
BN"9"151;
%"TAP"
"1","(-950,250)","2","standard","I15";
;
CDS_LIB"standard"
BODY_TYPE"PLUMBING"
HDL_TAP"TRUE";
"B \NAC \NWC"9;
"S \NAC"
BN"6"92;
%"TAP"
"1","(2475,3600)","0","standard","I150";
;
CDS_LIB"standard"
BODY_TYPE"PLUMBING"
HDL_TAP"TRUE";
"B \NAC \NWC"4;
"S \NAC"
BN"3"135;
%"TAP"
"1","(2475,3750)","0","standard","I151";
;
CDS_LIB"standard"
BODY_TYPE"PLUMBING"
HDL_TAP"TRUE";
"B \NAC \NWC"4;
"S \NAC"
BN"6"138;
%"TAP"
"1","(2475,3700)","0","standard","I152";
;
CDS_LIB"standard"
BODY_TYPE"PLUMBING"
HDL_TAP"TRUE";
"B \NAC \NWC"4;
"S \NAC"
BN"5"137;
%"TAP"
"1","(2475,3550)","0","standard","I153";
;
CDS_LIB"standard"
BODY_TYPE"PLUMBING"
HDL_TAP"TRUE";
"B \NAC \NWC"4;
"S \NAC"
BN"2"134;
%"TAP"
"1","(2475,3650)","0","standard","I154";
;
CDS_LIB"standard"
BODY_TYPE"PLUMBING"
HDL_TAP"TRUE";
"B \NAC \NWC"4;
"S \NAC"
BN"4"136;
%"TAP"
"1","(2475,3800)","0","standard","I155";
;
CDS_LIB"standard"
BODY_TYPE"PLUMBING"
HDL_TAP"TRUE";
"B \NAC \NWC"4;
"S \NAC"
BN"7"139;
%"TAP"
"1","(2475,3850)","0","standard","I156";
;
CDS_LIB"standard"
BODY_TYPE"PLUMBING"
HDL_TAP"TRUE";
"B \NAC \NWC"4;
"S \NAC"
BN"8"140;
%"TAP"
"1","(2475,3900)","0","standard","I157";
;
CDS_LIB"standard"
BODY_TYPE"PLUMBING"
HDL_TAP"TRUE";
"B \NAC \NWC"4;
"S \NAC"
BN"9"141;
%"TAP"
"1","(-950,300)","2","standard","I16";
;
CDS_LIB"standard"
BODY_TYPE"PLUMBING"
HDL_TAP"TRUE";
"B \NAC \NWC"9;
"S \NAC"
BN"7"91;
%"TAP"
"1","(-950,350)","2","standard","I17";
;
CDS_LIB"standard"
BODY_TYPE"PLUMBING"
HDL_TAP"TRUE";
"B \NAC \NWC"10;
"S \NAC"
BN"0"90;
%"TAP"
"1","(-950,400)","2","standard","I18";
;
CDS_LIB"standard"
BODY_TYPE"PLUMBING"
HDL_TAP"TRUE";
"B \NAC \NWC"10;
"S \NAC"
BN"1"89;
%"TAP"
"1","(-950,450)","2","standard","I19";
;
CDS_LIB"standard"
BODY_TYPE"PLUMBING"
HDL_TAP"TRUE";
"B \NAC \NWC"10;
"S \NAC"
BN"2"88;
%"TAP"
"1","(-950,500)","2","standard","I20";
;
CDS_LIB"standard"
BODY_TYPE"PLUMBING"
HDL_TAP"TRUE";
"B \NAC \NWC"10;
"S \NAC"
BN"3"87;
%"TAP"
"1","(-950,550)","2","standard","I21";
;
CDS_LIB"standard"
BODY_TYPE"PLUMBING"
HDL_TAP"TRUE";
"B \NAC \NWC"10;
"S \NAC"
BN"4"86;
%"TAP"
"1","(-950,650)","2","standard","I22";
;
CDS_LIB"standard"
BODY_TYPE"PLUMBING"
HDL_TAP"TRUE";
"B \NAC \NWC"10;
"S \NAC"
BN"6"84;
%"TAP"
"1","(-950,600)","2","standard","I23";
;
CDS_LIB"standard"
BODY_TYPE"PLUMBING"
HDL_TAP"TRUE";
"B \NAC \NWC"10;
"S \NAC"
BN"5"85;
%"TAP"
"1","(-950,700)","2","standard","I24";
;
CDS_LIB"standard"
BODY_TYPE"PLUMBING"
HDL_TAP"TRUE";
"B \NAC \NWC"10;
"S \NAC"
BN"7"83;
%"TAP"
"1","(-950,750)","2","standard","I25";
;
CDS_LIB"standard"
BODY_TYPE"PLUMBING"
HDL_TAP"TRUE";
"B \NAC \NWC"10;
"S \NAC"
BN"8"82;
%"TAP"
"1","(-950,800)","2","standard","I26";
;
CDS_LIB"standard"
BODY_TYPE"PLUMBING"
HDL_TAP"TRUE";
"B \NAC \NWC"10;
"S \NAC"
BN"9"81;
%"TAP"
"1","(-950,850)","2","standard","I27";
;
CDS_LIB"standard"
BODY_TYPE"PLUMBING"
HDL_TAP"TRUE";
"B \NAC \NWC"10;
"S \NAC"
BN"10"80;
%"TAP"
"1","(-950,900)","2","standard","I28";
;
CDS_LIB"standard"
BODY_TYPE"PLUMBING"
HDL_TAP"TRUE";
"B \NAC \NWC"10;
"S \NAC"
BN"11"79;
%"TAP"
"1","(-950,950)","2","standard","I29";
;
CDS_LIB"standard"
BODY_TYPE"PLUMBING"
HDL_TAP"TRUE";
"B \NAC \NWC"10;
"S \NAC"
BN"12"78;
%"TAP"
"1","(-950,-300)","2","standard","I3";
;
CDS_LIB"standard"
BODY_TYPE"PLUMBING"
HDL_TAP"TRUE";
"B \NAC \NWC"14;
"S \NAC"
BN"0"16;
%"TAP"
"1","(-950,1050)","2","standard","I30";
;
CDS_LIB"standard"
BODY_TYPE"PLUMBING"
HDL_TAP"TRUE";
"B \NAC \NWC"10;
"S \NAC"
BN"14"76;
%"TAP"
"1","(-950,1000)","2","standard","I31";
;
CDS_LIB"standard"
BODY_TYPE"PLUMBING"
HDL_TAP"TRUE";
"B \NAC \NWC"10;
"S \NAC"
BN"13"77;
%"TAP"
"1","(-950,1100)","2","standard","I32";
;
CDS_LIB"standard"
BODY_TYPE"PLUMBING"
HDL_TAP"TRUE";
"B \NAC \NWC"10;
"S \NAC"
BN"15"75;
%"TAP"
"1","(-950,1150)","2","standard","I33";
;
CDS_LIB"standard"
BODY_TYPE"PLUMBING"
HDL_TAP"TRUE";
"B \NAC \NWC"10;
"S \NAC"
BN"16"74;
%"TAP"
"1","(-950,1200)","2","standard","I34";
;
CDS_LIB"standard"
BODY_TYPE"PLUMBING"
HDL_TAP"TRUE";
"B \NAC \NWC"10;
"S \NAC"
BN"17"73;
%"TAP"
"1","(-950,1300)","2","standard","I35";
;
CDS_LIB"standard"
BODY_TYPE"PLUMBING"
HDL_TAP"TRUE";
"B \NAC \NWC"10;
"S \NAC"
BN"19"71;
%"TAP"
"1","(-950,1250)","2","standard","I36";
;
CDS_LIB"standard"
BODY_TYPE"PLUMBING"
HDL_TAP"TRUE";
"B \NAC \NWC"10;
"S \NAC"
BN"18"72;
%"TAP"
"1","(-950,1350)","2","standard","I37";
;
CDS_LIB"standard"
BODY_TYPE"PLUMBING"
HDL_TAP"TRUE";
"B \NAC \NWC"10;
"S \NAC"
BN"20"70;
%"TAP"
"1","(-950,1400)","2","standard","I38";
;
CDS_LIB"standard"
BODY_TYPE"PLUMBING"
HDL_TAP"TRUE";
"B \NAC \NWC"10;
"S \NAC"
BN"21"69;
%"TAP"
"1","(-950,1450)","2","standard","I39";
;
CDS_LIB"standard"
BODY_TYPE"PLUMBING"
HDL_TAP"TRUE";
"B \NAC \NWC"10;
"S \NAC"
BN"22"68;
%"TAP"
"1","(-950,-250)","2","standard","I4";
;
CDS_LIB"standard"
BODY_TYPE"PLUMBING"
HDL_TAP"TRUE";
"B \NAC \NWC"14;
"S \NAC"
BN"1"15;
%"TAP"
"1","(-950,1550)","2","standard","I40";
;
CDS_LIB"standard"
BODY_TYPE"PLUMBING"
HDL_TAP"TRUE";
"B \NAC \NWC"10;
"S \NAC"
BN"24"66;
%"TAP"
"1","(-950,1500)","2","standard","I41";
;
CDS_LIB"standard"
BODY_TYPE"PLUMBING"
HDL_TAP"TRUE";
"B \NAC \NWC"10;
"S \NAC"
BN"23"67;
%"TAP"
"1","(-950,1600)","2","standard","I42";
;
CDS_LIB"standard"
BODY_TYPE"PLUMBING"
HDL_TAP"TRUE";
"B \NAC \NWC"10;
"S \NAC"
BN"25"65;
%"TAP"
"1","(-950,1650)","2","standard","I43";
;
CDS_LIB"standard"
BODY_TYPE"PLUMBING"
HDL_TAP"TRUE";
"B \NAC \NWC"10;
"S \NAC"
BN"26"64;
%"TAP"
"1","(-950,1700)","2","standard","I44";
;
CDS_LIB"standard"
BODY_TYPE"PLUMBING"
HDL_TAP"TRUE";
"B \NAC \NWC"10;
"S \NAC"
BN"27"63;
%"TAP"
"1","(-950,1750)","2","standard","I45";
;
CDS_LIB"standard"
BODY_TYPE"PLUMBING"
HDL_TAP"TRUE";
"B \NAC \NWC"10;
"S \NAC"
BN"28"62;
%"TAP"
"1","(-950,1800)","2","standard","I46";
;
CDS_LIB"standard"
BODY_TYPE"PLUMBING"
HDL_TAP"TRUE";
"B \NAC \NWC"10;
"S \NAC"
BN"29"61;
%"TAP"
"1","(-950,1900)","2","standard","I47";
;
CDS_LIB"standard"
BODY_TYPE"PLUMBING"
HDL_TAP"TRUE";
"B \NAC \NWC"10;
"S \NAC"
BN"31"59;
%"TAP"
"1","(-950,1850)","2","standard","I48";
;
CDS_LIB"standard"
BODY_TYPE"PLUMBING"
HDL_TAP"TRUE";
"B \NAC \NWC"10;
"S \NAC"
BN"30"60;
%"TAP"
"1","(-950,1950)","2","standard","I49";
;
CDS_LIB"standard"
BODY_TYPE"PLUMBING"
HDL_TAP"TRUE";
"B \NAC \NWC"11;
"S \NAC"
BN"0"58;
%"TAP"
"1","(-950,-150)","2","standard","I5";
;
CDS_LIB"standard"
BODY_TYPE"PLUMBING"
HDL_TAP"TRUE";
"B \NAC \NWC"13;
"S \NAC"
BN"1"17;
%"TAP"
"1","(-950,2000)","2","standard","I52";
;
CDS_LIB"standard"
BODY_TYPE"PLUMBING"
HDL_TAP"TRUE";
"B \NAC \NWC"11;
"S \NAC"
BN"1"57;
%"TAP"
"1","(-950,2050)","2","standard","I53";
;
CDS_LIB"standard"
BODY_TYPE"PLUMBING"
HDL_TAP"TRUE";
"B \NAC \NWC"11;
"S \NAC"
BN"2"56;
%"TAP"
"1","(-950,2100)","2","standard","I54";
;
CDS_LIB"standard"
BODY_TYPE"PLUMBING"
HDL_TAP"TRUE";
"B \NAC \NWC"11;
"S \NAC"
BN"3"55;
%"TAP"
"1","(-950,2200)","2","standard","I55";
;
CDS_LIB"standard"
BODY_TYPE"PLUMBING"
HDL_TAP"TRUE";
"B \NAC \NWC"11;
"S \NAC"
BN"5"53;
%"TAP"
"1","(-950,2150)","2","standard","I56";
;
CDS_LIB"standard"
BODY_TYPE"PLUMBING"
HDL_TAP"TRUE";
"B \NAC \NWC"11;
"S \NAC"
BN"4"54;
%"TAP"
"1","(-950,2250)","2","standard","I57";
;
CDS_LIB"standard"
BODY_TYPE"PLUMBING"
HDL_TAP"TRUE";
"B \NAC \NWC"11;
"S \NAC"
BN"6"52;
%"TAP"
"1","(-950,2300)","2","standard","I58";
;
CDS_LIB"standard"
BODY_TYPE"PLUMBING"
HDL_TAP"TRUE";
"B \NAC \NWC"11;
"S \NAC"
BN"7"51;
%"TAP"
"1","(-950,2350)","2","standard","I59";
;
CDS_LIB"standard"
BODY_TYPE"PLUMBING"
HDL_TAP"TRUE";
"B \NAC \NWC"12;
"S \NAC"
BN"0"50;
%"TAP"
"1","(-950,-200)","2","standard","I6";
;
CDS_LIB"standard"
BODY_TYPE"PLUMBING"
HDL_TAP"TRUE";
"B \NAC \NWC"13;
"S \NAC"
BN"0"18;
%"TAP"
"1","(-950,2400)","2","standard","I60";
;
CDS_LIB"standard"
BODY_TYPE"PLUMBING"
HDL_TAP"TRUE";
"B \NAC \NWC"12;
"S \NAC"
BN"1"49;
%"TAP"
"1","(-950,2450)","2","standard","I61";
;
CDS_LIB"standard"
BODY_TYPE"PLUMBING"
HDL_TAP"TRUE";
"B \NAC \NWC"12;
"S \NAC"
BN"2"48;
%"TAP"
"1","(-950,2500)","2","standard","I62";
;
CDS_LIB"standard"
BODY_TYPE"PLUMBING"
HDL_TAP"TRUE";
"B \NAC \NWC"12;
"S \NAC"
BN"3"47;
%"TAP"
"1","(-950,2550)","2","standard","I63";
;
CDS_LIB"standard"
BODY_TYPE"PLUMBING"
HDL_TAP"TRUE";
"B \NAC \NWC"12;
"S \NAC"
BN"4"46;
%"TAP"
"1","(-950,2600)","2","standard","I64";
;
CDS_LIB"standard"
BODY_TYPE"PLUMBING"
HDL_TAP"TRUE";
"B \NAC \NWC"12;
"S \NAC"
BN"5"45;
%"TAP"
"1","(-950,2700)","2","standard","I65";
;
CDS_LIB"standard"
BODY_TYPE"PLUMBING"
HDL_TAP"TRUE";
"B \NAC \NWC"12;
"S \NAC"
BN"7"43;
%"TAP"
"1","(-950,2650)","2","standard","I66";
;
CDS_LIB"standard"
BODY_TYPE"PLUMBING"
HDL_TAP"TRUE";
"B \NAC \NWC"12;
"S \NAC"
BN"6"44;
%"TAP"
"1","(-950,2750)","2","standard","I67";
;
CDS_LIB"standard"
BODY_TYPE"PLUMBING"
HDL_TAP"TRUE";
"B \NAC \NWC"12;
"S \NAC"
BN"8"42;
%"TAP"
"1","(-950,2800)","2","standard","I68";
;
CDS_LIB"standard"
BODY_TYPE"PLUMBING"
HDL_TAP"TRUE";
"B \NAC \NWC"12;
"S \NAC"
BN"9"41;
%"TAP"
"1","(-950,2850)","2","standard","I69";
;
CDS_LIB"standard"
BODY_TYPE"PLUMBING"
HDL_TAP"TRUE";
"B \NAC \NWC"12;
"S \NAC"
BN"10"40;
%"TAP"
"1","(-950,2900)","2","standard","I70";
;
CDS_LIB"standard"
BODY_TYPE"PLUMBING"
HDL_TAP"TRUE";
"B \NAC \NWC"12;
"S \NAC"
BN"11"39;
%"TAP"
"1","(-950,2950)","2","standard","I71";
;
CDS_LIB"standard"
BODY_TYPE"PLUMBING"
HDL_TAP"TRUE";
"B \NAC \NWC"12;
"S \NAC"
BN"12"38;
%"TAP"
"1","(-950,3000)","2","standard","I72";
;
CDS_LIB"standard"
BODY_TYPE"PLUMBING"
HDL_TAP"TRUE";
"B \NAC \NWC"12;
"S \NAC"
BN"13"37;
%"TAP"
"1","(-950,3050)","2","standard","I73";
;
CDS_LIB"standard"
BODY_TYPE"PLUMBING"
HDL_TAP"TRUE";
"B \NAC \NWC"12;
"S \NAC"
BN"14"36;
%"TAP"
"1","(-950,3100)","2","standard","I74";
;
CDS_LIB"standard"
BODY_TYPE"PLUMBING"
HDL_TAP"TRUE";
"B \NAC \NWC"12;
"S \NAC"
BN"15"35;
%"TAP"
"1","(-950,3200)","2","standard","I75";
;
CDS_LIB"standard"
BODY_TYPE"PLUMBING"
HDL_TAP"TRUE";
"B \NAC \NWC"12;
"S \NAC"
BN"17"33;
%"TAP"
"1","(-950,3150)","2","standard","I76";
;
CDS_LIB"standard"
BODY_TYPE"PLUMBING"
HDL_TAP"TRUE";
"B \NAC \NWC"12;
"S \NAC"
BN"16"34;
%"TAP"
"1","(-950,3250)","2","standard","I77";
;
CDS_LIB"standard"
BODY_TYPE"PLUMBING"
HDL_TAP"TRUE";
"B \NAC \NWC"12;
"S \NAC"
BN"18"32;
%"TAP"
"1","(-950,3350)","2","standard","I78";
;
CDS_LIB"standard"
BODY_TYPE"PLUMBING"
HDL_TAP"TRUE";
"B \NAC \NWC"12;
"S \NAC"
BN"20"30;
%"TAP"
"1","(-950,3300)","2","standard","I79";
;
CDS_LIB"standard"
BODY_TYPE"PLUMBING"
HDL_TAP"TRUE";
"B \NAC \NWC"12;
"S \NAC"
BN"19"31;
%"TAP"
"1","(-950,3450)","2","standard","I80";
;
CDS_LIB"standard"
BODY_TYPE"PLUMBING"
HDL_TAP"TRUE";
"B \NAC \NWC"12;
"S \NAC"
BN"22"28;
%"TAP"
"1","(-950,3400)","2","standard","I81";
;
CDS_LIB"standard"
BODY_TYPE"PLUMBING"
HDL_TAP"TRUE";
"B \NAC \NWC"12;
"S \NAC"
BN"21"29;
%"TAP"
"1","(-950,3500)","2","standard","I82";
;
CDS_LIB"standard"
BODY_TYPE"PLUMBING"
HDL_TAP"TRUE";
"B \NAC \NWC"12;
"S \NAC"
BN"23"27;
%"TAP"
"1","(-950,3600)","2","standard","I83";
;
CDS_LIB"standard"
BODY_TYPE"PLUMBING"
HDL_TAP"TRUE";
"B \NAC \NWC"12;
"S \NAC"
BN"25"25;
%"TAP"
"1","(-950,3550)","2","standard","I84";
;
CDS_LIB"standard"
BODY_TYPE"PLUMBING"
HDL_TAP"TRUE";
"B \NAC \NWC"12;
"S \NAC"
BN"24"26;
%"TAP"
"1","(-950,3700)","2","standard","I85";
;
CDS_LIB"standard"
BODY_TYPE"PLUMBING"
HDL_TAP"TRUE";
"B \NAC \NWC"12;
"S \NAC"
BN"27"23;
%"TAP"
"1","(-950,3650)","2","standard","I86";
;
CDS_LIB"standard"
BODY_TYPE"PLUMBING"
HDL_TAP"TRUE";
"B \NAC \NWC"12;
"S \NAC"
BN"26"24;
%"TAP"
"1","(-950,3750)","2","standard","I87";
;
CDS_LIB"standard"
BODY_TYPE"PLUMBING"
HDL_TAP"TRUE";
"B \NAC \NWC"12;
"S \NAC"
BN"28"22;
%"TAP"
"1","(-950,3800)","2","standard","I88";
;
CDS_LIB"standard"
BODY_TYPE"PLUMBING"
HDL_TAP"TRUE";
"B \NAC \NWC"12;
"S \NAC"
BN"29"21;
%"TAP"
"1","(-950,3850)","2","standard","I89";
;
CDS_LIB"standard"
BODY_TYPE"PLUMBING"
HDL_TAP"TRUE";
"B \NAC \NWC"12;
"S \NAC"
BN"30"20;
%"TAP"
"1","(-950,0)","2","standard","I9";
;
CDS_LIB"standard"
BODY_TYPE"PLUMBING"
HDL_TAP"TRUE";
"B \NAC \NWC"9;
"S \NAC"
BN"1"97;
%"TAP"
"1","(-950,3900)","2","standard","I90";
;
CDS_LIB"standard"
BODY_TYPE"PLUMBING"
HDL_TAP"TRUE";
"B \NAC \NWC"12;
"S \NAC"
BN"31"19;
%"SOCKET4677_AZIF0045P001C01CS"
"9","(775,1800)","0","pure_quanta","I91";
;
PART_NUMBER"DGA^7000023"
PART_TYPE"SMLF"
MATERIAL"IO"
VALUE"SOCKET4677_AZIF0045-P001C01CS"
$LOCATION"U1"
CDS_LIB"pure_quanta"
NEEDS_NO_SIZE"TRUE"
CDS_LMAN_SYM_OUTLINE"-1100,2250,1050,-2250"
CDS_LOCATION"U1"
$SEC"9"
CDS_SEC"9";
"DDR1_SB_PAR"
$PN"P42"99;
"DDR1_SB_ECC0"
$PN"J35"98;
"DDR1_SB_ECC1"
$PN"K34"97;
"DDR1_SB_ECC2"
$PN"N35"96;
"DDR1_SB_ECC3"
$PN"M34"95;
"DDR1_SB_ECC4"
$PN"K38"94;
"DDR1_SB_ECC5"
$PN"J37"93;
"DDR1_SB_ECC6"
$PN"M38"92;
"DDR1_SB_ECC7"
$PN"N37"91;
"DDR1_SB_DQS_DP0"
$PN"U27"100;
"DDR1_SB_DQS_DP1"
$PN"K24"101;
"DDR1_SB_DQS_DP2"
$PN"K18"102;
"DDR1_SB_DQS_DP3"
$PN"C15"103;
"DDR1_SB_DQS_DP4"
$PN"M36"104;
"DDR1_SB_DQS_DP5"
$PN"AA27"105;
"DDR1_SB_DQS_DP6"
$PN"P24"106;
"DDR1_SB_DQS_DP7"
$PN"P18"107;
"DDR1_SB_DQS_DP8"
$PN"G15"108;
"DDR1_SB_DQS_DP9"
$PN"H36"109;
"DDR1_SB_DQS_DN0 \B"
$PN"R27"110;
"DDR1_SB_DQS_DN1 \B"
$PN"H24"111;
"DDR1_SB_DQS_DN2 \B"
$PN"H18"112;
"DDR1_SB_DQS_DN3 \B"
$PN"A15"113;
"DDR1_SB_DQS_DN4 \B"
$PN"P36"114;
"DDR1_SB_DQS_DN5 \B"
$PN"W27"115;
"DDR1_SB_DQS_DN6 \B"
$PN"M24"116;
"DDR1_SB_DQS_DN7 \B"
$PN"M18"117;
"DDR1_SB_DQS_DN8 \B"
$PN"E15"118;
"DDR1_SB_DQS_DN9 \B"
$PN"K36"119;
"DDR1_SB_DQ0"
$PN"U29"90;
"DDR1_SB_DQ1"
$PN"T28"89;
"DDR1_SB_DQ2"
$PN"W29"88;
"DDR1_SB_DQ3"
$PN"Y28"87;
"DDR1_SB_DQ4"
$PN"T26"86;
"DDR1_SB_DQ5"
$PN"U25"85;
"DDR1_SB_DQ6"
$PN"Y26"84;
"DDR1_SB_DQ7"
$PN"W25"83;
"DDR1_SB_DQ8"
$PN"K26"82;
"DDR1_SB_DQ9"
$PN"J25"81;
"DDR1_SB_DQ10"
$PN"M26"80;
"DDR1_SB_DQ11"
$PN"N25"79;
"DDR1_SB_DQ12"
$PN"J23"78;
"DDR1_SB_DQ13"
$PN"K22"77;
"DDR1_SB_DQ14"
$PN"N23"76;
"DDR1_SB_DQ15"
$PN"M22"75;
"DDR1_SB_DQ16"
$PN"K20"74;
"DDR1_SB_DQ17"
$PN"J19"73;
"DDR1_SB_DQ18"
$PN"M20"72;
"DDR1_SB_DQ19"
$PN"N19"71;
"DDR1_SB_DQ20"
$PN"J17"70;
"DDR1_SB_DQ21"
$PN"K16"69;
"DDR1_SB_DQ22"
$PN"N17"68;
"DDR1_SB_DQ23"
$PN"M16"67;
"DDR1_SB_DQ24"
$PN"C17"66;
"DDR1_SB_DQ25"
$PN"B16"65;
"DDR1_SB_DQ26"
$PN"E17"64;
"DDR1_SB_DQ27"
$PN"F16"63;
"DDR1_SB_DQ28"
$PN"C13"62;
"DDR1_SB_DQ29"
$PN"E13"61;
"DDR1_SB_DQ30"
$PN"B14"60;
"DDR1_SB_DQ31"
$PN"F14"59;
"DDR1_SB_CS_N0 \B"
$PN"J41"120;
"DDR1_SB_CS_N1 \B"
$PN"K40"121;
"DDR1_SB_CS_N2 \B"
$PN"N41"122;
"DDR1_SB_CS_N3 \B"
$PN"M40"123;
"DDR1_SB_CA0"
$PN"T44"124;
"DDR1_SB_CA1"
$PN"U43"125;
"DDR1_SB_CA2"
$PN"K44"126;
"DDR1_SB_CA3"
$PN"M44"127;
"DDR1_SB_CA4"
$PN"J43"128;
"DDR1_SB_CA5"
$PN"N43"129;
"DDR1_SB_CA6"
$PN"H42"130;
"DDR1_SA_PAR"
$PN"W43"131;
"DDR1_SA_ECC0"
$PN"K57"58;
"DDR1_SA_ECC1"
$PN"J56"57;
"DDR1_SA_ECC2"
$PN"M57"56;
"DDR1_SA_ECC3"
$PN"N56"55;
"DDR1_SA_ECC4"
$PN"J54"54;
"DDR1_SA_ECC5"
$PN"K53"53;
"DDR1_SA_ECC6"
$PN"N54"52;
"DDR1_SA_ECC7"
$PN"M53"51;
"DDR1_SA_DQS_DP0"
$PN"K73"132;
"DDR1_SA_DQS_DP1"
$PN"U70"133;
"DDR1_SA_DQS_DP2"
$PN"K61"134;
"DDR1_SA_DQS_DP3"
$PN"U58"135;
"DDR1_SA_DQS_DP4"
$PN"K55"136;
"DDR1_SA_DQS_DP5"
$PN"P73"137;
"DDR1_SA_DQS_DP6"
$PN"W70"138;
"DDR1_SA_DQS_DP7"
$PN"P61"139;
"DDR1_SA_DQS_DP8"
$PN"W58"140;
"DDR1_SA_DQS_DP9"
$PN"P55"141;
"DDR1_SA_DQS_DN0 \B"
$PN"H73"142;
"DDR1_SA_DQS_DN1 \B"
$PN"R70"143;
"DDR1_SA_DQS_DN2 \B"
$PN"H61"144;
"DDR1_SA_DQS_DN3 \B"
$PN"R58"145;
"DDR1_SA_DQS_DN4 \B"
$PN"H55"146;
"DDR1_SA_DQS_DN5 \B"
$PN"M73"147;
"DDR1_SA_DQS_DN6 \B"
$PN"AA70"148;
"DDR1_SA_DQS_DN7 \B"
$PN"M61"149;
"DDR1_SA_DQS_DN8 \B"
$PN"AA58"150;
"DDR1_SA_DQS_DN9 \B"
$PN"M55"151;
"DDR1_SA_DQ0"
$PN"K75"50;
"DDR1_SA_DQ1"
$PN"J74"49;
"DDR1_SA_DQ2"
$PN"M75"48;
"DDR1_SA_DQ3"
$PN"N74"47;
"DDR1_SA_DQ4"
$PN"J72"46;
"DDR1_SA_DQ5"
$PN"K71"45;
"DDR1_SA_DQ6"
$PN"N72"44;
"DDR1_SA_DQ7"
$PN"M71"43;
"DDR1_SA_DQ8"
$PN"U72"42;
"DDR1_SA_DQ9"
$PN"T71"41;
"DDR1_SA_DQ10"
$PN"W72"40;
"DDR1_SA_DQ11"
$PN"Y71"39;
"DDR1_SA_DQ12"
$PN"T69"38;
"DDR1_SA_DQ13"
$PN"U68"37;
"DDR1_SA_DQ14"
$PN"Y69"36;
"DDR1_SA_DQ15"
$PN"W68"35;
"DDR1_SA_DQ16"
$PN"K63"34;
"DDR1_SA_DQ17"
$PN"J62"33;
"DDR1_SA_DQ18"
$PN"M63"32;
"DDR1_SA_DQ19"
$PN"N62"31;
"DDR1_SA_DQ20"
$PN"J60"30;
"DDR1_SA_DQ21"
$PN"K59"29;
"DDR1_SA_DQ22"
$PN"N60"28;
"DDR1_SA_DQ23"
$PN"M59"27;
"DDR1_SA_DQ24"
$PN"U60"26;
"DDR1_SA_DQ25"
$PN"T59"25;
"DDR1_SA_DQ26"
$PN"W60"24;
"DDR1_SA_DQ27"
$PN"Y59"23;
"DDR1_SA_DQ28"
$PN"T57"22;
"DDR1_SA_DQ29"
$PN"U56"21;
"DDR1_SA_DQ30"
$PN"Y57"20;
"DDR1_SA_DQ31"
$PN"W56"19;
"DDR1_SA_CS_N0 \B"
$PN"K51"152;
"DDR1_SA_CS_N1 \B"
$PN"J50"153;
"DDR1_SA_CS_N2 \B"
$PN"M51"154;
"DDR1_SA_CS_N3 \B"
$PN"N50"155;
"DDR1_SA_CA0"
$PN"H49"156;
"DDR1_SA_CA1"
$PN"P49"157;
"DDR1_SA_CA2"
$PN"J48"158;
"DDR1_SA_CA3"
$PN"N48"159;
"DDR1_SA_CA4"
$PN"K47"160;
"DDR1_SA_CA5"
$PN"M47"161;
"DDR1_SA_CA6"
$PN"Y44"162;
"DDR1_CLK_DP0"
$PN"U45"18;
"DDR1_CLK_DP1"
$PN"AA45"17;
"DDR1_CLK_DN0 \B"
$PN"R45"16;
"DDR1_CLK_DN1 \B"
$PN"W45"15;
"DDR1_B_RSP0"
$PN"AN48"163;
"DDR1_B_RSP1"
$PN"AP47"164;
"DDR1_A_RSP0"
$PN"AL48"165;
"DDR1_A_RSP1"
$PN"AK47"166;
"DDR1_ALERT_N \B"
$PN"AV49"167;
%"TAP"
"1","(2475,150)","0","standard","I96";
;
CDS_LIB"standard"
BODY_TYPE"PLUMBING"
HDL_TAP"TRUE";
"B \NAC \NWC"6;
"S \NAC"
BN"0"120;
%"TAP"
"1","(2475,200)","0","standard","I97";
;
CDS_LIB"standard"
BODY_TYPE"PLUMBING"
HDL_TAP"TRUE";
"B \NAC \NWC"6;
"S \NAC"
BN"1"121;
%"TAP"
"1","(2475,300)","0","standard","I98";
;
CDS_LIB"standard"
BODY_TYPE"PLUMBING"
HDL_TAP"TRUE";
"B \NAC \NWC"6;
"S \NAC"
BN"3"123;
%"TAP"
"1","(2475,250)","0","standard","I99";
;
CDS_LIB"standard"
BODY_TYPE"PLUMBING"
HDL_TAP"TRUE";
"B \NAC \NWC"6;
"S \NAC"
BN"2"122;
END.
